TITLE: Bill of Materials
DATE: 03/29/2023
DESIGN: scm
TEMPLATE: c:\cadence\spb_17.2\share\cdssetup\template.bom
CALLOUT: 

S.No.,PART_NUMBER,DESCRIPTION,MATERIAL,Qty,MANUFTR,MANUF_PN,Ref Des,QPN,LIFECYCLE,STANDARD
0,AJ021000T03,ICOTHER(256P)LCMXO3LF-2100C-5BG256(CABGA,IC,1,LSC,LCMXO3LF-2100C-5BG256C,U25,?,?,?
1,AJ026000T06,IC(624P)AST2600A3-GP(TFBGA),IC,1,APD,AST2600A3-GP,U5,?,?,?
2,AKD5FGUT502,IC SDRAM(96P)K4A8G165WC-BCTD(FBGA)QBCON,IC,1,SAM,K4A8G165WC-BCTD,U1,?,?,?
3,AKE30Z0K610,IC(8P)M24128-BWDW6TP(TSSOP),IC,1,SGT,M24128-BWDW6TP,U19,?,?,?
4,AKE3FF00Z00,IC FLASH(16P)MX25L51245GMI-10G(SOP),EMPTY,1,MAX,MX25L51245GMI-10G,U17,?,Comp-Approve,End of Design
5,AL000257K00,IC OTHER(16P)IDTQS3VH257PAG(TSSOP),IC,2,?,IDTQS3VH257PAG,"U21,U30",?,?,?
6,AL000380K00,IC OTHER(6P)NCP380HSNAJAAT1G(TSOP-6),IC,1,ONS,NCP380HSNAJAAT1G,U10,?,?,?
7,AL000695001,IC CTRL(13P)NB695GD-Z(QFN-13),IC,2,MPS,NB695GD-Z,"PU41,PU42",?,?,?
8,AL001G07003,IC OTHER(5P)MC74VHC1G07DFT2G(SOT-353),EMPTY,1,ONS,MC74VHC1G07DFT2G,U13,?,?,?
9,AL001G14017,IC(5P) SN74LVC1G14DCKR(SC70),IC,1,?,?,U55,?,?,?
10,AL001G32031,IC OTHER (5P)MC74VHC1G32DTT1G(SOT-23),IC,4,ONS,MC74VHC1G32DTT1G,"U9,U42,U49,U58",?,?,?
11,AL001G66000,IC(5P) 74LVC1G66GV(SOT753),IC,1,PHI,74LVC1G66GV,U28,?,?,?
12,AL002205001,IC OTHER(5P)AP2205-W5-7(SOT25),IC,1,DDS,AP2205-W5-7,U56,?,?,?
13,AL002G07003,IC OTHER(6P)74LVC2G07DW-7(SOT-363),IC,3,DDS,74LVC2G07DW-7,"U6,U24,U47",?,?,?
14,AL003212003,IC OTHER(20P) PI3PCIE3212ZBEX(QFN),IC,1,PIM,PI3PCIE3212ZBEX,U22,?,?,?
15,AL003357009,IC OTHER(8P)FSA3357K8X(US8),IC,2,FAC,FSA3357K8X,"U2,U3",?,?,?
16,AL003808005,IC OTHER(6P)TPS3808G01DBVR(SOT23),IC,1,TIC,TPS3808G01DBVR,U43,?,?,?
17,AL008626000,IC CTRL(14P)MPQ8626GD-Z(QFN),IC,1,MPS,MPQ8626GD-Z,PU1,?,?,?
18,AL008633007,IC CTRL(21P)MPQ8633AGLE-C807-Z(QFN),IC,1,MPS,MPQ8633AGLE-C807-Z,PU38,?,?,?
19,AL009059000,IC OTHER(10P) RT9059GQW(WDFN),IC,2,RTK,RT9059GQW,"U39,U41",?,?,?
20,AL009517K00,IC OTHER (8P) PCA9517ADP(TSSOP8),IC,1,?,?,U37,?,?,?
21,AL022811000,IC OTHER(5P)AP22811AW5-7(SOT25),IC,1,DDS,AP22811AW5-7,U14,?,?,?
22,AL1G0007016,IC OTHER(5P)SN74LVC1G07DCKR(SOT),IC,1,TIC,SN74LVC1G07DCKR,U44,?,?,?
23,AL1G0017K01,IC OTHER(5P) 74LVC1G17GW(TSSOP),IC,1,NXP,74LVC1G17GW,U32,?,?,?
24,AL1G0074K01,IC OTHER(8P) 74LVC1G74DP (TSSOP8),IC,1,NXP,74LVC1G74DP,U54,?,?,?
25,AL1G0126007,IC(5P) 74HC1G126GW(SOT353)EP,IC,4,PHI,74HC1G126GW,"U26,U29,U33,U36",?,?,?
26,AL1G0126009,IC OTHER(5P) 74LVC1G126SE-7 (SOT353),IC,1,DDS,74LVC1G126SE-7,U8,?,?,?
27,AL5V0U2X000,IC OTHER (4P) PRTR5V0U2X (SOT143B),IC,1,NXP,PRTR5V0U2X,U38,?,?,?
28,ALSB3157000,IC(6P) NC7SB3157P6X(SC70-6),IC,4,?,NC7SB3157P6X,"U7,U20,U50,U51",?,Comp-Approve,End of Design
29,ALVC1G07001,IC(5P)74LVC1G07W5-7(SOT25),IC,1,DDS,74LVC1G07W5-7,U23,?,?,?
30,ALVC1G07002,IC(5P) 74LVC1G07GW(SOT353),EMPTY,1,PHI,74LVC1G07GW,U16,?,?,?
31,ALVC1G07002,IC(5P) 74LVC1G07GW(SOT353),IC,2,PHI,74LVC1G07GW,"U31,U57",?,?,?
32,ALVC1G08009,IC(5P) 74LVC1G08GW (SC70-5),IC,4,?,?,"U15,U18,U52,U53",?,Comp-Approve,End of Design
33,BA0390400H0,"TRANS SMD MMBT3904-7-F(40V,200MA,8W)",IC,2,DDS,MMBT3904-7-F,"Q1,Q3",?,Comp-Approve,End of Design
34,BAM138K0000,"TRANS MOS BSS138K(50V,0.22A,0.35W)",IC,1,?,BSS138K,U12,?,Comp-Approve,End of Design
35,BAM138K0003,"TRANS MOSFET PJT138K(50V,0.36A,0.236W)",IC,2,PJT,PJT138K,"Q9,Q13",?,?,?
36,BAM1P020000,"TRANS MOSFET NTR1P02LT1G(-20V,SOT-23)",EMPTY,1,ONS,NTR1P02LT1G,Q4,?,Comp-Approve,End of Design
37,BAM41410005,"TRANS MOS NTGS4141NT1G(30V,7.0A,TSOP6)",IC,1,ONS,NTGS4141NT1G,Q5,?,Comp-Approve,End of Design
38,BAM69680000,"TRANS MOS DMG6968U-7(20V,6.5A,1.3W)SOT23",IC,1,DDS,DMG6968U-7,Q10,?,Comp-Approve,End of Design
39,BAM70020047,"TRANS MOS 2N7002KDW(60V115MA,0.2W)SOT363",IC,2,PJT,2N7002KDW,"Q2,Q12",?,?,?
40,BAM70020062,"TRANS MOS NX7002AK(60V,0.19A,0.325W)SMD",IC,1,NXP,NX7002AK,Q11,?,Comp-Approve,End of Design
41,BAM70020068,"TRANS MOS 2N7002A-7(60V,0.115A,0.25W)",IC,3,DDS,2N7002A-7,"Q6,Q7,Q8",?,?,?
42,BC000340033,"DIODE SMD SDMK0340L-7-F(40V,30MA)",IC,1,?,?,D17,?,?,?
43,BC000340033,"DIODE SMD SDMK0340L-7-F(40V,30MA)",EMPTY,1,?,?,D23,?,?,?
44,BC001240Z01,DIODE ARRAY DT1240E-04LP-7 (3.3V),IC,3,DDS,DT1240E-04LP-7,"U27,U34,U35",?,?,?
45,BC00511TZ00,"DIODE SMD TVS UCLAMP0511T(5V,SLP1006P2T)",IC,1,STH,UCLAMP0511T.TCT,D10,?,?,?
46,BC005819Z40,DIODE SMD 1N5819HW-7-F(40V.1A.SOD123),IC,1,DDS,1N5819HW-7-F,D20,?,Comp-Approve,End of Design
47,BC0BAS70Z01,"DIODE SMD BAS70-05-7-F(70V,SHTKY,SOT-23)",IC,1,DDS,BAS70-05-7-F,U48,?,Comp-Approve,End of Design
48,BCBAT54CZ04,"DIODE SMD BAT54C(30V,0.2A,SCHOTTKY)",IC,1,PJT,BAT54C,U11,?,Comp-Approve,End of Design
49,BCSBA130Z00,"DIODE SMD SBA130Q(30V,1A,SCHOTTKY)",EMPTY,1,PJT,SBA130Q,D16,?,?,?
50,BCSS0530Z00,"DIODE SMD SS0530(30V,0.5A)SOD-123",IC,1,PJT,SS0530,D11,?,?,?
51,BCSS0530Z00,"DIODE SMD SS0530(30V,0.5A)SOD-123",EMPTY,1,PJT,SS0530,D9,?,?,?
52,BCZA462AZ01,"DIODE SMD BZA462A(6.2V,100MA,SOT457)",EMPTY,1,PHI,BZA462A,D12,?,?,?
53,BEBL0172Z00,LED SMD(2P) BLUE(LTST-C281TBKT-5A),IC,2,?,LTST-C281TBKT-5A,"D18,D19",?,?,?
54,BEBL0277D00,LED DIP(2P)BLUE(HV-312470/260/SUBD-TR1),IC,4,?,HV-312470/260/SUBD-TR1,"D14,D15,D21,D22",?,?,?
55,BEGR0278Z00,LED SMD(2P) GREEN(19-213/GVC-AMNB/3T),IC,5,?,19-213/GVC-AMNB/3T,"D0,D1,D2,D3,D8",?,?,?
56,BERD0034Z07,LED SMD(2P) RED (19-217/R6C-P1Q2/3T),IC,4,?,19-217/R6C-P1Q2/3T,"D4,D5,D6,D7",?,?,?
57,BEYL0182D00,LED DIP(2P)YELLOW(LTL-R42FSFADH213T),IC,1,?,LTL-R42FSFADH213T,D13,?,?,?
58,BF625000023,"OSC SMD 25MHZ(+-25PPM,3.3V)7X25000018",MISC,2,TXC,7X25000018,"OSC1,OSC2",?,?,?
59,CH0106F0B00,CHIP0402,NPO,2,?,?,"C211,C212",?,?,?
60,CH01506JB06,CAP CHIP 15P 50V(+-5% C0G 0402),C0G,3,?,?,"C205,C206,C207",?,?,?
61,CH01806JB07,CAP CHIP 18P 50V(+-5% C0G 0402),C0G,1,?,?,C209,?,?,?
62,CH02206JB08,CHIP0402,NPO,2,?,?,"C208,C210",?,?,?
63,CH06806JB01,CAP CHIP 68P 50V(+-5%.COG.0402),COG,1,?,?,PC272,?,?,?
64,CH11006JB00,"CAP CHIP 100P 50V(+-5%,NPO,0402)",NPO,3,?,?,"C9,C275,PC239",?,?,?
65,CH11006JB18,CAP CHIP 100P 50V(+-5%.X7R.0402),EMPTY,2,?,?,"C213,C214",?,Comp-Approve,End of Design
66,CH14706KB18,CHIP0402,X7R,5,?,?,"C172,C178,C179,C324,C326",?,?,?
67,CH22206KB16,"CAP CHIP 2200P 50V(+-10%,X7R,0402)",X7R,2,?,?,"C63,C173",?,?,?
68,CH2336K1B12,CHIP0402,X7R,1,?,?,PC273,?,?,?
69,CH2474K1B08,"CAP CHIP 4700P 25V(+-10%,X7R,0402)MUR",EMPTY,1,?,?,C223,?,?,?
70,CH30106KB19,"CAP CHIP 0.001U 50V(10%,X7R,0402)",EMPTY,6,?,?,"C150,C151,C153,C154,C155,C156",?,Comp-Release Qty,End of Design
71,CH31006KB18,"CAP CHIP 0.01U 50V(+-10%,X7R,0402)",X7R,8,?,?,"C133,C134,C135,C136,C137,C138,C170,C246",?,?,?
72,CH31006KB18,"CAP CHIP 0.01U 50V(+-10%,X7R,0402)",EMPTY,6,?,?,"C21,C169,C281,C283,C285,C286",?,?,?
73,CH4104K1B00,"CAP CHIP 0.1U 25V(+-10%,X7R,0402)",X7R,173,?,?,"C6,C7,C8,C10,C11,C13,C14,C17,C18,C19,C20,C22,C23,C24,C25,C26,C27,C31,C33,C34,C36,C37,C39,C41,C45,C49,C50,C51,C54,C57,C59,C65,C66,C68,C69,C70,C71,C72,C73,C74,C76,C77,C79,C81,C82,C83,C84,C85,C86,C87,C88,C89,C91,C92,C93,C94,C95,C96,C97,C98,C99,C100,C101,C102,C103,C105,C107,C109,C112,C130,C139,C140,C141,C144,C146,C148,C149,C152,C157,C158,C159,C160,C162,C167,C168,C175,C180,C181,C187,C188,C189,C190,C191,C192,C193,C197,C200,C201,C202,C203,C217,C219,C220,C221,C222,C225,C231,C236,C237,C240,C241,C242,C243,C245,C247,C249,C250,C251,C253,C254,C255,C257,C260,C261,C262,C263,C264,C266,C268,C269,C271,C272,C274,C276,C278,C279,C280,C284,C290,C291,C294,C295,C296,C297,C298,C299,C300,C301,C302,C303,C304,C307,C309,C311,C312,C313,C314,C318,C321,C336,C337,C500,C501,PC205,PC210,PC212,PC223,PC225,PC253,PC255,PC263,PC266,PC271",?,?,?
74,CH4104K1B00,"CAP CHIP 0.1U 25V(+-10%,X7R,0402)",EMPTY,7,?,?,"C29,C147,C174,C228,C235,C238,C239",?,?,?
75,CH4223K1B00,"CAP CHIP 0.22U 16V(10%,X7R,0402)",X7R,5,?,?,"C12,PC216,PC224,PC254,PC264",?,Comp-Approve,End of Design
76,CH4223K1B00,"CAP CHIP 0.22U 16V(10%,X7R,0402)",EMPTY,1,?,?,C229,?,Comp-Approve,End of Design
77,CH5103K1900,CHIP0603,EMPTY,1,?,?,C204,?,Comp-Approve,End of Design
78,CH5103K9B00,CHIP0402,EMPTY,3,?,?,"C267,C270,C273",?,Comp-Approve,End of Design
79,CH5104KEB02,"CAP CHIP 1UF 25V(+-10%,X6S,0402)",X6S,65,?,?,"C2,C3,C4,C5,C30,C32,C35,C38,C43,C46,C47,C48,C52,C53,C56,C58,C60,C61,C62,C64,C67,C75,C78,C80,C90,C104,C106,C108,C110,C111,C114,C115,C116,C117,C119,C122,C127,C128,C129,C145,C161,C164,C165,C166,C176,C195,C196,C198,C199,C216,C218,C226,C244,C256,C277,C282,C287,C292,C305,C310,C335,PC208,PC221,PC250,PC260",?,?,?
80,CH5104KEB02,"CAP CHIP 1UF 25V(+-10%,X6S,0402)",EMPTY,2,?,?,"C28,C252",?,?,?
81,CH5222KEB01,"CAP CHIP 2.2UF 10V(+-10%,X6S,0402)",X6S,1,?,?,C227,?,?,?
82,CH5474KE906,"CAP CHIP 4.7UF 25V(+-10%,X6S,0603)",X6S,3,?,?,"C1,C40,C44",?,?,?
83,CH6101MEB01,"CAP CHIP 10UF 6.3V(+-20%,X6S,0402)",X6S,6,?,?,"C15,C16,C143,C215,C224,C248",?,?,?
84,CH6103ME902,"CAP CHIP 10U 16V(+-20%,X6S,0603)",X6S,2,?,?,"C163,C194",?,?,?
85,CH6104KEA00,"CAP CHIP 10U 25V(+-10%,X6S,0805,H1.25)",X6S,8,?,?,"C142,C288,C289,C293,PC251,PC252,PC261,PC262",?,?,?
86,CH6221ME900,"CAP CHIP 22U 6.3V(+-20%,X6S,0603)",X6S,12,?,?,"C42,C55,C113,C118,C120,C121,C123,C124,C125,C126,C131,C132",?,?,?
87,CH6222M9901,"CAP CHIP 22UF 10V(+-20%,X5R,0603)",EMPTY,1,?,?,C234,?,?,?
88,CH6222MEA00,"CAP CHIP 22U 10V(+-20%,X6S,0805)",X6S,9,?,?,"C171,PC213,PC214,PC215,PC217,PC226,PC227,PC228,PC229",?,?,?
89,CH6223MEA01,"CAP CHIP 22UF 16V(+-20%,X6S,0805)MUR",X6S,7,?,?,"C265,C329,C330,PC206,PC207,PC218,PC219",?,?,?
90,CH622KMEA01,CHIP0805,X6S,8,?,?,"PC256,PC257,PC258,PC259,PC267,PC268,PC269,PC270",?,Comp-Approve,End of Design
91,CH6471ME200,"CAP CHIP 47U 6.3V(+-20%,X6S,1206)",X6S,2,?,?,"C177,C327",?,Comp-Approve,End of Design
92,CS-2202FB01,RES CHIP 2.2 1/16W +-1%(0402)EF,CHIP,1,?,?,R415,?,Comp-Approve,End of Design
93,CS-5102JB02,RES CHIP 5.1 1/16W +-5%(0402)EF,CHIP,2,?,?,"PR539,PR541",?,?,?
94,CS00002JB13,RES CHIP 0 1/16W +-5%(0402)EF,CHIP,154,?,?,"PR193,PR274,R2,R3,R10,R18,R19,R20,R30,R35,R39,R49,R51,R57,R83,R84,R85,R86,R95,R97,R98,R99,R105,R109,R110,R113,R114,R134,R135,R155,R182,R183,R207,R213,R217,R218,R220,R231,R271,R272,R275,R276,R277,R279,R281,R282,R292,R293,R294,R301,R303,R304,R305,R307,R308,R316,R317,R318,R320,R321,R322,R323,R379,R381,R382,R385,R386,R392,R393,R395,R397,R398,R399,R432,R447,R450,R451,R453,R454,R456,R457,R471,R500,R503,R505,R519,R525,R527,R528,R544,R545,R546,R560,R566,R571,R574,R575,R577,R578,R579,R616,R618,R626,R629,R632,R634,R636,R637,R666,R668,R669,R670,R671,R672,R673,R674,R675,R676,R695,R696,R697,R698,R700,R701,R702,R703,R707,R708,R720,R721,R722,R726,R728,R731,R732,R733,R734,R746,R747,R748,R779,R783,R804,R822,R838,R847,R853,R882,R898,R899,R900,R901,R902,R903",?,Comp-Approve,End of Design
95,CS00002JB13,RES CHIP 0 1/16W +-5%(0402)EF,EMPTY,35,?,?,"PR205,PR275,R1,R63,R64,R106,R154,R156,R208,R214,R232,R278,R280,R315,R463,R470,R564,R711,R719,R764,R780,R781,R782,R784,R811,R868,R869,R871,R872,R873,R874,R875,R876,R877,R878",?,Comp-Approve,End of Design
96,CS00003J910,RES CHIP 0 1/10W +-5% (0603)EF,EMPTY,3,?,?,"R27,R645,R646",?,Comp-Approve,End of Design
97,CS01002FB07,RES CHIP 10 1/16W +-1%(0402)EF,CHIP,3,?,?,"R21,R24,R26",?,Comp-Approve,End of Design
98,CS02202FB02,RES CHIP 22 1/16W +-1%(0402)EF,CHIP,13,?,?,"R128,R129,R130,R131,R171,R172,R173,R498,R499,R860,R861,R862,R863",?,Comp-Approve,End of Design
99,CS03302FB19,RES CHIP 33 1/16W +-1%(0402),EMPTY,10,?,?,"R48,R532,R647,R648,R649,R650,R651,R652,R653,R654",?,Comp-Approve,End of Design
100,CS03322FB03,RES CHIP 33.2 1/16W +-1%(0402)EF,CHIP,197,?,?,"R28,R29,R33,R36,R37,R46,R47,R60,R65,R70,R71,R93,R96,R100,R102,R104,R111,R112,R119,R120,R121,R122,R123,R132,R133,R137,R139,R142,R143,R144,R146,R147,R148,R150,R151,R152,R153,R157,R158,R159,R160,R162,R165,R166,R168,R170,R174,R175,R176,R177,R178,R179,R180,R185,R187,R199,R201,R215,R221,R222,R223,R224,R236,R237,R242,R243,R263,R270,R300,R302,R309,R310,R311,R388,R390,R394,R401,R402,R405,R407,R421,R423,R424,R425,R426,R427,R433,R434,R435,R436,R437,R439,R442,R443,R444,R445,R448,R449,R455,R458,R459,R460,R461,R465,R466,R469,R479,R481,R482,R483,R484,R485,R486,R489,R494,R501,R509,R510,R511,R512,R513,R514,R515,R516,R517,R518,R536,R537,R547,R548,R549,R550,R551,R552,R553,R555,R556,R559,R562,R567,R570,R580,R582,R583,R584,R585,R589,R590,R594,R635,R638,R639,R643,R644,R688,R690,R691,R693,R705,R713,R715,R718,R724,R725,R750,R752,R757,R759,R760,R761,R762,R763,R766,R767,R769,R773,R799,R801,R802,R807,R812,R813,R824,R825,R826,R827,R833,R836,R837,R840,R841,R849,R850,R859,R864,R880,R884",?,Comp-Approve,End of Design
101,CS03322FB03,RES CHIP 33.2 1/16W +-1%(0402)EF,EMPTY,9,?,?,"R526,R531,R561,R678,R679,R680,R681,R682,R689",?,Comp-Approve,End of Design
102,CS04022FB28,RES CHIP 40.2 1/16W +-1%(0402),CHIP,1,?,?,R138,?,Comp-Approve,End of Design
103,CS04992FB07,RES CHIP 49.9 1/16W +-1%(0402)EF,CHIP,5,?,?,"R108,R192,R216,R409,R410",?,Comp-Approve,End of Design
104,CS04992FB07,RES CHIP 49.9 1/16W +-1%(0402)EF,EMPTY,2,?,?,"R440,R441",?,Comp-Approve,End of Design
105,CS06042FB03,RES CHIP 60.4 1/16W +-1%(0402)EF,CHIP,2,?,?,"R7,R8",?,Comp-Approve,End of Design
106,CS06812FB03,RES CHIP 68.1 1/16W +-1%(0402)EF,CHIP,1,?,?,R852,?,Comp-Approve,End of Design
107,CS07502FB04,RES CHIP 75 1/16W +-1%(0402)EF,CHIP,2,?,?,"R283,R284",?,Comp-Approve,End of Design
108,CS09092FB15,RES CHIP 90.9 1/16W +-1%(0402),CHIP,1,?,?,R468,?,Comp-Approve,End of Design
109,CS11002FB07,RES CHIP 100 1/16W +-1%(0402)EF,CHIP,12,?,?,"R125,R225,R380,R384,R411,R412,R413,R529,R530,R565,R628,R694",?,Comp-Approve,End of Design
110,CS11002FB07,RES CHIP 100 1/16W +-1%(0402)EF,EMPTY,7,?,?,"R164,R431,R506,R507,R743,R744,R745",?,Comp-Approve,End of Design
111,CS11102FB03,RES CHIP 110 1/16W +-1%(0402)EF,CHIP,4,?,?,"R184,R186,R198,R200",?,?,?
112,CS11202FB02,RES CHIP 120 1/16W +-1%(0402)EF,CHIP,48,?,?,"R326,R327,R328,R329,R330,R331,R332,R333,R334,R335,R336,R337,R338,R339,R340,R341,R342,R343,R344,R345,R346,R347,R348,R349,R351,R352,R353,R354,R355,R356,R357,R358,R359,R360,R361,R362,R363,R364,R365,R366,R367,R368,R369,R370,R371,R372,R373,R374",?,Comp-Approve,End of Design
113,CS11202FB02,RES CHIP 120 1/16W +-1%(0402)EF,EMPTY,2,?,?,"R350,R375",?,Comp-Approve,End of Design
114,CS11502FB07,RES CHIP 150 1/16W +-1%(0402)EF,CHIP,7,?,?,"R22,R23,R25,R87,R88,R89,R420",?,Comp-Approve,End of Design
115,CS12002FB06,RES CHIP 200 1/16W +-1%(0402)EF,CHIP,1,?,?,R879,?,Comp-Approve,End of Design
116,CS12202FB04,RES CHIP 220 1/16W +-1%(0402)EF,CHIP,4,?,?,"R43,R80,R568,R569",?,?,?
117,CS12402FB01,RES CHIP 240 1/16W +-1%(0402)EF,CHIP,2,?,?,"R6,R127",?,Comp-Approve,End of Design
118,CS13162FB01,RES CHIP 316 1/16W +-1%(0402)EF,CHIP,3,?,?,"R107,R286,R389",?,?,?
119,CS13302FB00,RES CHIP 330 1/16W +-1%(0402)EF,CHIP,1,?,?,R167,?,Comp-Approve,End of Design
120,CS14992FB06,RES CHIP 499 1/16W +-1%(0402)EF,CHIP,2,?,?,"R251,R287",?,Comp-Approve,End of Design
121,CS16652FB00,RES CHIP 665 1/16W +-1%(0402)EF,CHIP,1,?,?,R793,?,Comp-Approve,End of Design
122,CS17502FB03,RES CHIP 750 1/16W +-1%(0402)EF,CHIP,8,?,?,"R597,R598,R599,R600,R601,R602,R603,R604",?,Comp-Approve,End of Design
123,CS21002FB06,RES CHIP 1K 1/16W +-1%(0402)EF,CHIP,21,?,?,"R4,R5,R15,R188,R189,R190,R191,R194,R195,R196,R197,R210,R324,R325,R419,R735,R736,R775,R795,R796,R857",?,Comp-Approve,End of Design
124,CS21002FB06,RES CHIP 1K 1/16W +-1%(0402)EF,EMPTY,9,?,?,"R53,R73,R77,R417,R633,R855,R865,R867,R888",?,Comp-Approve,End of Design
125,CS21002FB24,RES CHIP 1K 1/16W +-1% (0402),EMPTY,4,?,?,"R664,R665,R684,R685",?,Comp-Approve,End of Design
126,CS21692FB04,RES CHIP 1.69K 1/16W +-1%(0402)EF,CHIP,1,?,?,R791,?,Comp-Approve,End of Design
127,CS21802FB10,RES CHIP 1.8K 1/16W +-1%(0402),CHIP,2,?,?,"R244,R245",?,Comp-Approve,End of Design
128,CS22002FB07,RES CHIP 2K 1/16W +-1%(0402)EF,CHIP,16,?,?,"R74,R75,R76,R78,R79,R82,R124,R467,R714,R751,R786,R788,R790,R792,R794,R798",?,Comp-Approve,End of Design
129,CS22002FB07,RES CHIP 2K 1/16W +-1%(0402)EF,EMPTY,1,?,?,R40,?,Comp-Approve,End of Design
130,CS22202JB07,RES CHIP 2.2K 1/16W +-5%(0402)EF,CHIP,21,?,?,"R91,R92,R246,R247,R248,R249,R252,R253,R256,R257,R258,R259,R264,R265,R422,R428,R429,R438,R610,R692,R709",?,Comp-Approve,End of Design
131,CS22212FB06,RES CHIP 2.21K 1/16W +-1%(0402)EF,EMPTY,2,?,?,"R16,R17",?,Comp-Approve,End of Design
132,CS22742FB05,RES CHIP 2.74K 1/16W +-1%(0402)EF,CHIP,1,?,?,R235,?,Comp-Approve,End of Design
133,CS22872FB03,RES CHIP 2.87K 1/16W +-1%(0402)EF,CHIP,2,?,?,"R789,R797",?,Comp-Approve,End of Design
134,CS24702FB06,RES CHIP 4.7K 1/16W +-1%(0402)EF,CHIP,84,?,?,"R9,R11,R31,R32,R38,R42,R45,R52,R55,R56,R61,R62,R67,R68,R69,R72,R81,R94,R101,R103,R116,R161,R163,R169,R181,R212,R238,R239,R240,R241,R268,R269,R285,R291,R298,R299,R319,R376,R416,R430,R446,R452,R462,R488,R490,R492,R557,R558,R563,R586,R592,R607,R608,R621,R624,R625,R627,R630,R667,R683,R706,R717,R730,R738,R739,R740,R741,R749,R758,R765,R774,R805,R806,R816,R835,R842,R843,R844,R848,R851,R854,R858,R885,R886",?,Comp-Approve,End of Design
135,CS24702FB06,RES CHIP 4.7K 1/16W +-1%(0402)EF,EMPTY,35,?,?,"R12,R13,R14,R34,R44,R90,R115,R117,R140,R229,R266,R267,R400,R418,R472,R487,R491,R496,R593,R595,R623,R640,R641,R699,R737,R742,R753,R754,R770,R821,R828,R846,R856,R870,R887",?,Comp-Approve,End of Design
136,CS24702FB10,RES CHIP 4.7K 1/16W +-1%(0402),EMPTY,9,?,?,"R58,R408,R414,R543,R554,R615,R686,R687,R881",?,Comp-Approve,End of Design
137,CS25362FB02,RES CHIP 5.36K 1/16W +-1%(0402)EF,CHIP,1,?,?,R787,?,Comp-Approve,End of Design
138,CS25492FB02,RES CHIP 5.49K 1/16W +-1%(0402) EF,CHIP,1,?,?,PR276,?,Comp-Approve,End of Design
139,CS28202JB05,RES CHIP 8.2K 1/16W +-5% (0402) EF,EMPTY,3,?,?,"R391,R619,R883",?,Comp-Approve,End of Design
140,CS28202JB05,RES CHIP 8.2K 1/16W +-5% (0402) EF,CHIP,3,?,?,"R504,R768,R839",?,Comp-Approve,End of Design
141,CS31002FB08,RES CHIP 10K 1/16W +-1%(0402)EF,CHIP,46,?,?,"PR241,PR242,PR498,PR500,R50,R54,R59,R126,R136,R145,R149,R203,R204,R206,R211,R226,R227,R230,R250,R254,R255,R260,R261,R262,R288,R289,R295,R297,R306,R383,R403,R404,R406,R464,R497,R508,R521,R523,R677,R716,R808,R809,R810,R814,R815,R866",?,Comp-Approve,End of Design
142,CS31002FB08,RES CHIP 10K 1/16W +-1%(0402)EF,EMPTY,7,?,?,"R41,R202,R209,R228,R377,R712,R834",?,Comp-Approve,End of Design
143,CS31002FB26,RES CHIP 10K 1/16W +-1% (0402),EMPTY,9,?,?,"R655,R656,R657,R658,R659,R660,R661,R662,R663",?,Comp-Approve,End of Design
144,CS31202FB04,RES CHIP 12K 1/16W +-1%(0402)EF,CHIP,2,?,?,"R830,R832",?,Comp-Approve,End of Design
145,CS31242FB02,RES CHIP 12.4K 1/16W +-1%(0402)EF,CHIP,2,?,?,"PR526,PR530",?,Comp-Approve,End of Design
146,CS31502FB05,RES CHIP 15K 1/16W +-1%(0402)EF,CHIP,1,?,?,R831,?,Comp-Approve,End of Design
147,CS31582FB02,RES CHIP 15.8K 1/16W +-1% (0402)EF,CHIP,1,?,?,R785,?,Comp-Approve,End of Design
148,CS31692FB03,RES CHIP 16.9K 1/16W +-1%(0402)EF,CHIP,1,?,?,R631,?,Comp-Approve,End of Design
149,CS32002FB06,RES CHIP 20K 1/16W +-1%(0402)EF,CHIP,2,?,?,"R205,R378",?,Comp-Approve,End of Design
150,CS32052FB02,RES CHIP 20.5K 1/16W +-1%(0402)EF,CHIP,1,?,?,PR525,?,Comp-Approve,End of Design
151,CS32552FB06,RES CHIP 25.5K 1/16W +-1%(0402)EF,CHIP,1,?,?,R829,?,Comp-Approve,End of Design
152,CS34702FB01,RES CHIP 47K 1/16W +-1%(0402)EF,CHIP,3,?,?,"R290,R312,R776",?,Comp-Approve,End of Design
153,CS34992FB05,RES CHIP 49.9K 1/16W +-1%(0402)EF,CHIP,2,?,?,"R233,R234",?,Comp-Approve,End of Design
154,CS35602FB00,RES CHIP 56K 1/16W +-1%(0402)EF,CHIP,1,?,?,PR534,?,?,?
155,CS36042FB04,RES CHIP 60.4K 1/16W +-1%(0402)EF,CHIP,1,?,?,PR532,?,Comp-Approve,End of Design
156,CS39102FB06,RES CHIP 91K 1/16W +-1%(0402)EF,CHIP,1,?,?,PR527,?,?,?
157,CS41002FB09,RES CHIP 100K 1/16W +-1%(0402)EF,EMPTY,8,?,?,"PR245,R219,R274,R296,R817,R818,R819,R820",?,Comp-Approve,End of Design
158,CS41002FB09,RES CHIP 100K 1/16W +-1%(0402)EF,CHIP,16,?,?,"PR522,PR543,R66,R118,R193,R273,R314,R387,R396,R538,R614,R620,R642,R710,R778,R823",?,Comp-Approve,End of Design
159,CS41502FB04,RES CHIP 150K 1/16W +-1%(0402)EF,CHIP,1,?,?,PR496,?,Comp-Approve,End of Design
160,CS41502FB04,RES CHIP 150K 1/16W +-1%(0402)EF,EMPTY,1,?,?,R493,?,Comp-Approve,End of Design
161,CS42002FB05,RES CHIP 200K 1/16W +-1%(0402)EF,CHIP,1,?,?,R777,?,Comp-Approve,End of Design
162,CS44702FB02,RES CHIP 470K 1/16W +-1%(0402)EF,CHIP,1,?,?,R313,?,Comp-Approve,End of Design
163,CS46812FB06,RES CHIP 681K 1/16W +-1%(0402)EF,CHIP,1,?,?,PR521,?,?,?
164,CV-10B0MZ13,IND SMD 1UH 20%11A(PCMC063T-1R0MN),IND,2,?,?,"PL31,PL33",?,?,?
165,CV-3360MZ07,"IND SMD 3.3UH,6A20%(PCMC063T-3R3MN)",IND,1,?,?,PL35,?,?,?
166,CV-47A0MZ10,IND SMD 4.7UH +-20% 10A(PCMB104E-4R7MS),IND,1,?,?,PL34,?,?,?
167,CX21SN67000,"EMI FILTER DLW21SN670HQ2L(67,320MA)",EMPTY,3,MUR,DLW21SN670HQ2L,"L21,L22,L23",?,?,?
168,CX220TN1001,"EMI FILTER BLM18SN220TN1D(22,8000MA)",IND,4,?,?,"PL4,PL19,PL29,PL32",?,Comp-Approve,End of Design
169,CX8BB470007,EMI FILTER CHIP BLM18BB470(47.500MA),IND,3,?,?,"L28,L29,L30",?,?,?
170,CX8EG121000,EMI FILTER BLM18EG121SN1D(120.2A),IND,2,?,?,"L17,L19",?,?,?
171,CX8PG121009,"EMI FILTER BLM18PG121SN(120,2000MA)",IND,14,?,?,"L2,L3,L4,L5,L6,L7,L8,L10,L11,L12,L13,L14,L15,L16",?,?,?
172,CX8PG121009,"EMI FILTER BLM18PG121SN(120,2000MA)",EMPTY,1,?,?,L9,?,?,?
173,DFHD03MS161,"CONN SMD HEADER 3P 1R MS(P2.54,H9.3)",IO,1,PRX,212-H91-03GBR1,J1,?,?,?
174,DFHD03MS161,"CONN SMD HEADER 3P 1R MS(P2.54,H9.3)",EMPTY,1,PRX,212-H91-03GBR1,J13,?,?,?
175,DFHD03MS251,"CONN SMD HEADER 3P 1R MS(P2.54, H9.3)",EMPTY,1,PRX,212-91-035BR2,J6,?,?,?
176,DFHD08MS225,"CONN DIP HEADER 8P 2R MS(P2.54,H8.38)",EMPTY,1,STC,TSW-104-07-F-D,J14,?,?,?
177,DFHD08MS392,"CONN DIP HEADER 8P 1R MS(P2.54,H8.6)",IO,1,PRX,210-HP1-080BR1,J7,?,?,?
178,DFHD13MS080,"CONN SMD HEADER 13P 1R MS(P1.0,H4.3)",IO,1,ACS,50228-0130C-V01,J8,?,?,?
179,DFHS09FR401,"CONN DIP USB3.0 9P 2R FR(P2.0,H7.74)",IO,1,APL,GSB3111315HR,J2,?,?,?
180,DFHS11FS009,"CONN SMD HOUSING 11P 2R FS(P1,H3.28)",IO,2,BER,91920-31111LF,"J5,J10",?,?,?
181,DFHS75FR133,"CONN SMD HOUSING 75P 2R FR(P0.5,H6.7)",IO,1,LTK,NASA0-S6730-TS67,J4,?,?,?
182,DG016000006,"IC SOCKET SMD 16P(SPI,SOIC)(P1.27,H5.8)",IO,1,LTS,ACA-SPI-006-P06,J40,?,?,?
183,DHPDTSAM601,SWITCH TACT DTSAM-63N/K-S-Q-T/R,MECH,3,DIP,DTSAM-63N/K-S-Q-T/R,"SW6,SW7,SW8",?,?,?
184,DK110TPU003,FUSE SMD 1.1A 8V POLY(SMD1206P110TFT),EMPTY,1,?,?,FS1,?,?,?
185,DUMMY1,QUANTA_LOGO_7X26,EMPTY,1,?,?,ME1,?,?,?
186,DUMMY2,WEEE,EMPTY,1,?,?,ME2,?,?,?
187,DUMMY3,PB-E1_SMALL,EMPTY,1,?,?,DM7,?,?,?
188,DUMMY50,HOLE_TOOLINGD125N_T2-0,EMPTY,2,?,?,"H2B1,H2B2",?,?,?
189,DUMMY69,SNLABEL_7X7,EMPTY,1,?,?,ME4,?,?,?
190,DUMMY8,BMC_FLASH,EMPTY,2,?,?,"DM1,DM2",?,?,?
191,DUMMY9,BIOS_FLASH,MECH,1,?,?,DM3,?,?,?
192,GOLD244,GOLD_168P_ME1016810202011_SCM,EMPTY,1,APL,?,GF1,?,?,?
193,HOLE1211,HOLE_C6-03D3-13B6-03_NPB,EMPTY,2,?,?,"H5,H9",?,?,?
194,HOLE1247,HOLE_OB6-4X8OBD3-2X4-8B6-4X8N_RO6X7-6_NPM,EMPTY,1,?,?,H2,?,?,?
195,HOLE1248,HOLE_C4-5D3-8B8I5-6_RO6-6_NPT_RB,EMPTY,1,?,?,H1,?,?,?
196,HOLE620,HOLE_C6D3-4B6_NPB,EMPTY,2,?,?,"H3,H4",?,?,?
197,N_A,"(USE SYM_2)TDR 3PIN,2X141MIL 1X100MIL P2P",EMPTY,6,?,?,"DB1,DB2,DB3,DB4,DB5,DB6",?,?,?
198,N_A,DIFF_TEST_PAD DIP FOR FTS ONLY,EMPTY,16,?,?,"X1,X2,X5,X6,X7,X8,X11,X12,X13,X14,X17,X18,X19,X20,X23,X24",?,?,?
199,TMP-C_HOLE8,HOLE_C6-5D3-2,EMPTY,2,?,?,"H6,H7",?,?,?
200,TMP_QAL009555K04,IC(24P) PCA9555PW(TSSOP)EP,IC,1,?,?,U40,?,?,?
201,TP33,Probe for DELTA-L 4.0 measurement,EMPTY,16,?,?,"J9,J11,J12,J16,J17,J19,J20,J22,J23,J24,J25,J26,J27,J28,J29,J30",?,?,?
TOTAL, , , ,1428, , , , , , 
